(kicad_pcb
	(version 20260206)
	(generator "pcbnew")
	(generator_version "10.0")
	(general
		(thickness 1.6)
		(legacy_teardrops no)
	)
	(paper "A4")
	(title_block
		(title "Wiwynn_Tioga_Pass_MB.brd")
		(comment 1 "Tioga Pass / footprints 2417-2424 of 4770")
	)
	(layers
		(0 "F.Cu" signal "TOP")
		(4 "In1.Cu" signal "L2GND")
		(6 "In2.Cu" signal "L3")
		(8 "In3.Cu" signal "L4GND")
		(10 "In4.Cu" signal "L5")
		(12 "In5.Cu" signal "L6GND")
		(14 "In6.Cu" signal "L7VCC")
		(16 "In7.Cu" signal "L8VCC")
		(18 "In8.Cu" signal "L9GND")
		(20 "In9.Cu" signal "L10")
		(22 "In10.Cu" signal "L11GND")
		(24 "In11.Cu" signal "L12")
		(26 "In12.Cu" signal "L13GND")
		(2 "B.Cu" signal "BOTTOM")
		(9 "F.Adhes" user "F.Adhesive")
		(11 "B.Adhes" user "B.Adhesive")
		(13 "F.Paste" user "Package Geometry/Pastemask Top")
		(15 "B.Paste" user "Package Geometry/Pastemask Bottom")
		(5 "F.SilkS" user "Ref Des/Silkscreen Top")
		(7 "B.SilkS" user "Ref Des/Silkscreen Bottom")
		(1 "F.Mask" user "Board Geometry/Soldermask Top")
		(3 "B.Mask" user "Board Geometry/Soldermask Bottom")
		(17 "Dwgs.User" user "User.Drawings")
		(19 "Cmts.User" user "User.Comments")
		(21 "Eco1.User" user "User.Eco1")
		(23 "Eco2.User" user "User.Eco2")
		(25 "Edge.Cuts" user "Board Geometry/Outline")
		(27 "Margin" user)
		(31 "F.CrtYd" user "Package Geometry/Place Bound Top")
		(29 "B.CrtYd" user "Package Geometry/Place Bound Bottom")
		(35 "F.Fab" user "Ref Des/Assembly Top")
		(33 "B.Fab" user "Ref Des/Assembly Bottom")
	)
	(footprint ""
		(layer "B.Cu")
		(at 282.259024 -78.039214 -90)
		(property "Reference" "R4P3"
			(at 0 0 90)
			(layer "B.SilkS")
			(hide yes)
			(effects
				(font
					(size 1.27 1.27)
				)
				(justify mirror)
			)
		)
		(property "Value" ""
			(at 0 0 90)
			(layer "B.Fab")
			(effects
				(font
					(size 1.27 1.27)
				)
				(justify mirror)
			)
		)
		(duplicate_pad_numbers_are_jumpers no)
		(fp_rect
			(start 0.2794 0.9906)
			(end -0.2794 -0.1016)
			(stroke
				(width 0)
				(type default)
			)
			(fill no)
			(layer "B.CrtYd")
		)
		(fp_line
			(start -0.2794 0.9906)
			(end -0.2794 -0.1016)
			(stroke
				(width 0.1)
				(type default)
			)
			(layer "B.Fab")
		)
		(fp_line
			(start 0.2794 0.9906)
			(end -0.2794 0.9906)
			(stroke
				(width 0.1)
				(type default)
			)
			(layer "B.Fab")
		)
		(fp_line
			(start -0.2794 -0.1016)
			(end 0.2794 -0.1016)
			(stroke
				(width 0.1)
				(type default)
			)
			(layer "B.Fab")
		)
		(fp_line
			(start 0.2794 -0.1016)
			(end 0.2794 0.9906)
			(stroke
				(width 0.1)
				(type default)
			)
			(layer "B.Fab")
		)
		(pad "1" smd rect
			(at 0 0 90)
			(size 0.508 0.508)
			(layers "B.Cu" "B.Mask" "B.Paste")
			(net "A_CPU0_PE012_RBIAS")
		)
		(pad "2" smd rect
			(at 0 0.889 90)
			(size 0.508 0.508)
			(layers "B.Cu" "B.Mask" "B.Paste")
			(net "GND")
		)
		(zone
			(layer "B.Cu")
			(hatch none 0.5)
			(connect_pads
				(clearance 0)
			)
			(min_thickness 0.25)
			(keepout
				(tracks allowed)
				(vias not_allowed)
				(pads allowed)
				(copperpour not_allowed)
				(footprints allowed)
			)
			(placement
				(enabled no)
				(sheetname "")
			)
			(fill
				(thermal_gap 0.5)
				(thermal_bridge_width 0.5)
				(island_removal_mode 0)
			)
			(polygon
				(pts
					(xy 281.624024 -77.785214) (xy 282.005024 -77.785214) (xy 282.005024 -78.293214) (xy 281.624024 -78.293214)
				)
			)
		)
		(zone
			(layer "B.Cu")
			(hatch none 0.5)
			(connect_pads
				(clearance 0)
			)
			(min_thickness 0.25)
			(keepout
				(tracks not_allowed)
				(vias allowed)
				(pads allowed)
				(copperpour not_allowed)
				(footprints allowed)
			)
			(placement
				(enabled no)
				(sheetname "")
			)
			(fill
				(thermal_gap 0.5)
				(thermal_bridge_width 0.5)
				(island_removal_mode 0)
			)
			(polygon
				(pts
					(xy 281.624024 -77.785214) (xy 282.005024 -77.785214) (xy 282.005024 -78.293214) (xy 281.624024 -78.293214)
				)
			)
		)
	)
	(footprint ""
		(layer "B.Cu")
		(at 345.832176 -77.694536)
		(property "Reference" "C3P21"
			(at 0 0 0)
			(layer "B.SilkS")
			(hide yes)
			(effects
				(font
					(size 1.27 1.27)
				)
				(justify mirror)
			)
		)
		(property "Value" ""
			(at 0 0 0)
			(layer "B.Fab")
			(effects
				(font
					(size 1.27 1.27)
				)
				(justify mirror)
			)
		)
		(duplicate_pad_numbers_are_jumpers no)
		(fp_poly
			(pts
				(xy -0.3048 -0.1016) (xy -0.3048 0.9906) (xy 0.3048 0.9906) (xy 0.3048 -0.1016)
			)
			(stroke
				(width 0)
				(type default)
			)
			(fill no)
			(layer "B.CrtYd")
		)
		(fp_line
			(start -0.3048 -0.1016)
			(end 0.3048 -0.1016)
			(stroke
				(width 0.1)
				(type default)
			)
			(layer "B.Fab")
		)
		(fp_line
			(start -0.3048 0.9906)
			(end -0.3048 -0.1016)
			(stroke
				(width 0.1)
				(type default)
			)
			(layer "B.Fab")
		)
		(fp_line
			(start 0.3048 -0.1016)
			(end 0.3048 0.9906)
			(stroke
				(width 0.1)
				(type default)
			)
			(layer "B.Fab")
		)
		(fp_line
			(start 0.3048 0.9906)
			(end -0.3048 0.9906)
			(stroke
				(width 0.1)
				(type default)
			)
			(layer "B.Fab")
		)
		(pad "1" smd rect
			(at 0 0 180)
			(size 0.508 0.508)
			(layers "B.Cu" "B.Mask" "B.Paste")
			(net "P3E_CPU0_PE1_SS_TXN<2>")
		)
		(pad "2" smd rect
			(at 0 0.889 180)
			(size 0.508 0.508)
			(layers "B.Cu" "B.Mask" "B.Paste")
			(net "P3E_CPU0_PE1_SS_C_TXN<2>")
		)
		(zone
			(layer "B.Cu")
			(hatch none 0.5)
			(connect_pads
				(clearance 0)
			)
			(min_thickness 0.25)
			(keepout
				(tracks allowed)
				(vias not_allowed)
				(pads allowed)
				(copperpour not_allowed)
				(footprints allowed)
			)
			(placement
				(enabled no)
				(sheetname "")
			)
			(fill
				(thermal_gap 0.5)
				(thermal_bridge_width 0.5)
				(island_removal_mode 0)
			)
			(polygon
				(pts
					(xy 346.086176 -77.440536) (xy 345.578176 -77.440536) (xy 345.578176 -77.059536) (xy 346.086176 -77.059536)
				)
			)
		)
	)
	(footprint ""
		(layer "B.Cu")
		(at 244.5004 -27.813 -90)
		(property "Reference" "C5T1"
			(at 0 0 90)
			(layer "B.SilkS")
			(hide yes)
			(effects
				(font
					(size 1.27 1.27)
				)
				(justify mirror)
			)
		)
		(property "Value" ""
			(at 0 0 90)
			(layer "B.Fab")
			(effects
				(font
					(size 1.27 1.27)
				)
				(justify mirror)
			)
		)
		(duplicate_pad_numbers_are_jumpers no)
		(fp_rect
			(start 0.500126 1.598422)
			(end -0.500126 -0.201422)
			(stroke
				(width 0)
				(type default)
			)
			(fill no)
			(layer "B.CrtYd")
		)
		(fp_line
			(start -0.500126 1.598422)
			(end 0.500126 1.598422)
			(stroke
				(width 0.1)
				(type default)
			)
			(layer "B.Fab")
		)
		(fp_line
			(start 0.500126 1.598422)
			(end 0.500126 -0.201422)
			(stroke
				(width 0.1)
				(type default)
			)
			(layer "B.Fab")
		)
		(fp_line
			(start -0.500126 -0.201422)
			(end -0.500126 1.598422)
			(stroke
				(width 0.1)
				(type default)
			)
			(layer "B.Fab")
		)
		(fp_line
			(start 0.500126 -0.201422)
			(end -0.500126 -0.201422)
			(stroke
				(width 0.1)
				(type default)
			)
			(layer "B.Fab")
		)
		(pad "1" smd rect
			(at 0 0 180)
			(size 0.889 0.9906)
			(layers "B.Cu" "B.Mask" "B.Paste")
			(net "PVDDQ_ABC")
		)
		(pad "2" smd rect
			(at 0 1.397 180)
			(size 0.889 0.9906)
			(layers "B.Cu" "B.Mask" "B.Paste")
			(net "GND")
		)
		(zone
			(layer "B.Cu")
			(hatch none 0.5)
			(connect_pads
				(clearance 0)
			)
			(min_thickness 0.25)
			(keepout
				(tracks not_allowed)
				(vias allowed)
				(pads allowed)
				(copperpour not_allowed)
				(footprints allowed)
			)
			(placement
				(enabled no)
				(sheetname "")
			)
			(fill
				(thermal_gap 0.5)
				(thermal_bridge_width 0.5)
				(island_removal_mode 0)
			)
			(polygon
				(pts
					(xy 243.5479 -27.3177) (xy 244.0559 -27.3177) (xy 244.0559 -28.3083) (xy 243.5479 -28.3083)
				)
			)
		)
		(zone
			(layer "B.Cu")
			(hatch none 0.5)
			(connect_pads
				(clearance 0)
			)
			(min_thickness 0.25)
			(keepout
				(tracks allowed)
				(vias not_allowed)
				(pads allowed)
				(copperpour not_allowed)
				(footprints allowed)
			)
			(placement
				(enabled no)
				(sheetname "")
			)
			(fill
				(thermal_gap 0.5)
				(thermal_bridge_width 0.5)
				(island_removal_mode 0)
			)
			(polygon
				(pts
					(xy 243.5479 -27.3177) (xy 244.0559 -27.3177) (xy 244.0559 -28.3083) (xy 243.5479 -28.3083)
				)
			)
		)
	)
	(footprint ""
		(layer "B.Cu")
		(at 189.992 -54.229 90)
		(property "Reference" "C22W17"
			(at 0 0 90)
			(layer "B.SilkS")
			(hide yes)
			(effects
				(font
					(size 1.27 1.27)
				)
				(justify mirror)
			)
		)
		(property "Value" "*"
			(at 0.0762 -6.2357 90)
			(unlocked yes)
			(layer "B.Fab")
			(hide yes)
			(effects
				(font
					(size 1.27 1.016)
					(thickness 0.1524)
				)
				(justify mirror)
			)
		)
		(property "Device Type" "SC22U16V5MX-4-GP_SMD-BCG5-SC22A"
			(at 0.0762 -8.2677 90)
			(unlocked yes)
			(layer "B.Fab")
			(hide yes)
			(effects
				(font
					(size 1.27 1.016)
					(thickness 0.1524)
				)
				(justify mirror)
			)
		)
		(duplicate_pad_numbers_are_jumpers no)
		(fp_line
			(start -0.635 0)
			(end 0.635 0)
			(stroke
				(width 0.508)
				(type default)
			)
			(layer "B.SilkS")
		)
		(fp_rect
			(start 0.9652 1.778)
			(end -0.9652 -1.778)
			(stroke
				(width 0)
				(type default)
			)
			(fill no)
			(layer "B.CrtYd")
		)
		(fp_poly
			(pts
				(xy 0.9652 -1.778) (xy -0.9652 -1.778) (xy -0.9652 1.778) (xy 0.9652 1.778)
			)
			(stroke
				(width 0)
				(type default)
			)
			(fill no)
			(layer "B.Fab")
		)
		(pad "1" smd rect
			(at 0 -0.9652 270)
			(size 1.397 1.143)
			(layers "B.Cu" "B.Mask" "B.Paste")
			(net "VR_FET_SW_P12V_STBY_PVCCIN_CPU0")
		)
		(pad "2" smd rect
			(at 0 0.9652 270)
			(size 1.397 1.143)
			(layers "B.Cu" "B.Mask" "B.Paste")
			(net "GND")
		)
	)
	(footprint ""
		(layer "B.Cu")
		(at 267.552424 -85.075014)
		(property "Reference" "C5P1"
			(at 0 0 0)
			(layer "B.SilkS")
			(hide yes)
			(effects
				(font
					(size 1.27 1.27)
				)
				(justify mirror)
			)
		)
		(property "Value" ""
			(at 0 0 0)
			(layer "B.Fab")
			(effects
				(font
					(size 1.27 1.27)
				)
				(justify mirror)
			)
		)
		(duplicate_pad_numbers_are_jumpers no)
		(fp_poly
			(pts
				(xy 0.7239 -0.2159) (xy -0.7239 -0.2159) (xy -0.7239 1.9939) (xy 0.7239 1.9939)
			)
			(stroke
				(width 0)
				(type default)
			)
			(fill no)
			(layer "B.CrtYd")
		)
		(fp_line
			(start -0.7239 -0.2159)
			(end 0.7239 -0.2159)
			(stroke
				(width 0.1)
				(type default)
			)
			(layer "B.Fab")
		)
		(fp_line
			(start -0.7239 1.9939)
			(end -0.7239 -0.2159)
			(stroke
				(width 0.1)
				(type default)
			)
			(layer "B.Fab")
		)
		(fp_line
			(start 0.7239 -0.2159)
			(end 0.7239 1.9939)
			(stroke
				(width 0.1)
				(type default)
			)
			(layer "B.Fab")
		)
		(fp_line
			(start 0.7239 1.9939)
			(end -0.7239 1.9939)
			(stroke
				(width 0.1)
				(type default)
			)
			(layer "B.Fab")
		)
		(pad "1" smd rect
			(at 0 0 180)
			(size 1.27 1.016)
			(layers "B.Cu" "B.Mask" "B.Paste")
			(net "PVDDQ_DEF")
		)
		(pad "2" smd rect
			(at 0 1.778 180)
			(size 1.27 1.016)
			(layers "B.Cu" "B.Mask" "B.Paste")
			(net "GND")
		)
		(zone
			(layer "B.Cu")
			(hatch none 0.5)
			(connect_pads
				(clearance 0)
			)
			(min_thickness 0.25)
			(keepout
				(tracks not_allowed)
				(vias allowed)
				(pads allowed)
				(copperpour not_allowed)
				(footprints allowed)
			)
			(placement
				(enabled no)
				(sheetname "")
			)
			(fill
				(thermal_gap 0.5)
				(thermal_bridge_width 0.5)
				(island_removal_mode 0)
			)
			(polygon
				(pts
					(xy 268.187424 -84.567014) (xy 266.917424 -84.567014) (xy 266.917424 -83.805014) (xy 268.187424 -83.805014)
				)
			)
		)
	)
	(footprint ""
		(layer "B.Cu")
		(at 481.203 -114.554 90)
		(property "Reference" "C1M21"
			(at 0 0 90)
			(layer "B.SilkS")
			(hide yes)
			(effects
				(font
					(size 1.27 1.27)
				)
				(justify mirror)
			)
		)
		(property "Value" ""
			(at 0 0 90)
			(layer "B.Fab")
			(effects
				(font
					(size 1.27 1.27)
				)
				(justify mirror)
			)
		)
		(duplicate_pad_numbers_are_jumpers no)
		(fp_rect
			(start 0.3048 -0.1016)
			(end -0.3048 0.9906)
			(stroke
				(width 0)
				(type default)
			)
			(fill no)
			(layer "B.CrtYd")
		)
		(fp_line
			(start 0.3048 -0.1016)
			(end 0.3048 0.9906)
			(stroke
				(width 0.1)
				(type default)
			)
			(layer "B.Fab")
		)
		(fp_line
			(start -0.3048 -0.1016)
			(end 0.3048 -0.1016)
			(stroke
				(width 0.1)
				(type default)
			)
			(layer "B.Fab")
		)
		(fp_line
			(start 0.3048 0.9906)
			(end -0.3048 0.9906)
			(stroke
				(width 0.1)
				(type default)
			)
			(layer "B.Fab")
		)
		(fp_line
			(start -0.3048 0.9906)
			(end -0.3048 -0.1016)
			(stroke
				(width 0.1)
				(type default)
			)
			(layer "B.Fab")
		)
		(pad "1" smd rect
			(at 0 0 270)
			(size 0.508 0.508)
			(layers "B.Cu" "B.Mask" "B.Paste")
			(net "P3V3")
		)
		(pad "2" smd rect
			(at 0 0.889 270)
			(size 0.508 0.508)
			(layers "B.Cu" "B.Mask" "B.Paste")
			(net "GND")
		)
		(zone
			(layer "B.Cu")
			(hatch none 0.5)
			(connect_pads
				(clearance 0)
			)
			(min_thickness 0.25)
			(keepout
				(tracks allowed)
				(vias not_allowed)
				(pads allowed)
				(copperpour not_allowed)
				(footprints allowed)
			)
			(placement
				(enabled no)
				(sheetname "")
			)
			(fill
				(thermal_gap 0.5)
				(thermal_bridge_width 0.5)
				(island_removal_mode 0)
			)
			(polygon
				(pts
					(xy 481.457 -114.808) (xy 481.457 -114.3) (xy 481.838 -114.3) (xy 481.838 -114.808)
				)
			)
		)
		(zone
			(layer "B.Cu")
			(hatch none 0.5)
			(connect_pads
				(clearance 0)
			)
			(min_thickness 0.25)
			(keepout
				(tracks not_allowed)
				(vias allowed)
				(pads allowed)
				(copperpour not_allowed)
				(footprints allowed)
			)
			(placement
				(enabled no)
				(sheetname "")
			)
			(fill
				(thermal_gap 0.5)
				(thermal_bridge_width 0.5)
				(island_removal_mode 0)
			)
			(polygon
				(pts
					(xy 481.457 -114.808) (xy 481.457 -114.3) (xy 481.838 -114.3) (xy 481.838 -114.808)
				)
			)
		)
	)
	(footprint ""
		(layer "B.Cu")
		(at 410.464 -149.06752 90)
		(property "Reference" "C2L20"
			(at 0 0 90)
			(layer "B.SilkS")
			(hide yes)
			(effects
				(font
					(size 1.27 1.27)
				)
				(justify mirror)
			)
		)
		(property "Value" ""
			(at 0 0 90)
			(layer "B.Fab")
			(effects
				(font
					(size 1.27 1.27)
				)
				(justify mirror)
			)
		)
		(duplicate_pad_numbers_are_jumpers no)
		(fp_poly
			(pts
				(xy -0.3048 -0.1016) (xy -0.3048 0.9906) (xy 0.3048 0.9906) (xy 0.3048 -0.1016)
			)
			(stroke
				(width 0)
				(type default)
			)
			(fill no)
			(layer "B.CrtYd")
		)
		(fp_line
			(start 0.3048 -0.1016)
			(end 0.3048 0.9906)
			(stroke
				(width 0.1)
				(type default)
			)
			(layer "B.Fab")
		)
		(fp_line
			(start -0.3048 -0.1016)
			(end 0.3048 -0.1016)
			(stroke
				(width 0.1)
				(type default)
			)
			(layer "B.Fab")
		)
		(fp_line
			(start 0.3048 0.9906)
			(end -0.3048 0.9906)
			(stroke
				(width 0.1)
				(type default)
			)
			(layer "B.Fab")
		)
		(fp_line
			(start -0.3048 0.9906)
			(end -0.3048 -0.1016)
			(stroke
				(width 0.1)
				(type default)
			)
			(layer "B.Fab")
		)
		(pad "1" smd rect
			(at 0 0 270)
			(size 0.508 0.508)
			(layers "B.Cu" "B.Mask" "B.Paste")
			(net "SATA6G_PCH_PCIE_UP_SATA_RXP<4>")
		)
		(pad "2" smd rect
			(at 0 0.889 270)
			(size 0.508 0.508)
			(layers "B.Cu" "B.Mask" "B.Paste")
			(net "SATA6G_P4_RX_C_DP")
		)
		(zone
			(layer "B.Cu")
			(hatch none 0.5)
			(connect_pads
				(clearance 0)
			)
			(min_thickness 0.25)
			(keepout
				(tracks allowed)
				(vias not_allowed)
				(pads allowed)
				(copperpour not_allowed)
				(footprints allowed)
			)
			(placement
				(enabled no)
				(sheetname "")
			)
			(fill
				(thermal_gap 0.5)
				(thermal_bridge_width 0.5)
				(island_removal_mode 0)
			)
			(polygon
				(pts
					(xy 410.718 -149.32152) (xy 410.718 -148.81352) (xy 411.099 -148.81352) (xy 411.099 -149.32152)
				)
			)
		)
		(zone
			(layer "B.Cu")
			(hatch none 0.5)
			(connect_pads
				(clearance 0)
			)
			(min_thickness 0.25)
			(keepout
				(tracks not_allowed)
				(vias allowed)
				(pads allowed)
				(copperpour not_allowed)
				(footprints allowed)
			)
			(placement
				(enabled no)
				(sheetname "")
			)
			(fill
				(thermal_gap 0.5)
				(thermal_bridge_width 0.5)
				(island_removal_mode 0)
			)
			(polygon
				(pts
					(xy 411.099 -149.32152) (xy 411.099 -148.81352) (xy 410.718 -148.81352) (xy 410.718 -149.32152)
				)
			)
		)
	)
	(footprint ""
		(layer "B.Cu")
		(at 409.884118 -92.860114 180)
		(property "Reference" "Q3U1"
			(at -2.737104 -0.459232 90)
			(unlocked yes)
			(layer "B.SilkS")
			(effects
				(font
					(size 0.7874 0.5842)
					(thickness 0.1524)
				)
				(justify left mirror)
			)
		)
		(property "Value" ""
			(at 0 0 0)
			(layer "B.Fab")
			(effects
				(font
					(size 1.27 1.27)
				)
				(justify mirror)
			)
		)
		(duplicate_pad_numbers_are_jumpers no)
		(fp_circle
			(center 0.508 -0.7874)
			(end 0.381 -0.7874)
			(stroke
				(width 0.254)
				(type default)
			)
			(fill no)
			(layer "B.SilkS")
		)
		(fp_poly
			(pts
				(xy -0.2159 1.7526) (xy -1.5621 1.7526) (xy -1.5621 -0.4572) (xy -0.2159 -0.4572)
			)
			(stroke
				(width 0)
				(type default)
			)
			(fill no)
			(layer "B.CrtYd")
		)
		(fp_line
			(start -0.2159 1.75514)
			(end -1.5621 1.75514)
			(stroke
				(width 0.1)
				(type default)
			)
			(layer "B.Fab")
		)
		(fp_line
			(start -0.2159 -0.45466)
			(end -0.2159 1.75514)
			(stroke
				(width 0.1)
				(type default)
			)
			(layer "B.Fab")
		)
		(fp_line
			(start -1.5621 1.75514)
			(end -1.5621 -0.45466)
			(stroke
				(width 0.1)
				(type default)
			)
			(layer "B.Fab")
		)
		(fp_line
			(start -1.5621 -0.45466)
			(end -0.2159 -0.45466)
			(stroke
				(width 0.1)
				(type default)
			)
			(layer "B.Fab")
		)
		(fp_circle
			(center 0.508 -0.7874)
			(end 0.381 -0.7874)
			(stroke
				(width 0.254)
				(type default)
			)
			(fill no)
			(layer "B.Fab")
		)
		(pad "1" smd rect
			(at 0 0)
			(size 1.016 0.381)
			(layers "B.Cu" "B.Mask" "B.Paste")
			(net "GND")
		)
		(pad "2" smd rect
			(at 0 0.65024)
			(size 1.016 0.381)
			(layers "B.Cu" "B.Mask" "B.Paste")
			(net "IRQ_PVDDQ_ABC_VRHOT_LVT3_N")
		)
		(pad "3" smd rect
			(at 0 1.30048)
			(size 1.016 0.381)
			(layers "B.Cu" "B.Mask" "B.Paste")
			(net "H_CPU0_MEMABC_MEMHOT_G_N")
		)
		(pad "4" smd rect
			(at -1.778 1.30048)
			(size 1.016 0.381)
			(layers "B.Cu" "B.Mask" "B.Paste")
			(net "GND")
		)
		(pad "5" smd rect
			(at -1.778 0.65024)
			(size 1.016 0.381)
			(layers "B.Cu" "B.Mask" "B.Paste")
			(net "H_CPU0_MEMABC_MEMHOT")
		)
		(pad "6" smd rect
			(at -1.778 0)
			(size 1.016 0.381)
			(layers "B.Cu" "B.Mask" "B.Paste")
			(net "H_CPU0_MEMABC_MEMHOT")
		)
		(zone
			(layer "B.Cu")
			(hatch none 0.5)
			(connect_pads
				(clearance 0)
			)
			(min_thickness 0.25)
			(keepout
				(tracks allowed)
				(vias not_allowed)
				(pads allowed)
				(copperpour not_allowed)
				(footprints allowed)
			)
			(placement
				(enabled no)
				(sheetname "")
			)
			(fill
				(thermal_gap 0.5)
				(thermal_bridge_width 0.5)
				(island_removal_mode 0)
			)
			(polygon
				(pts
					(xy 409.376118 -92.669614) (xy 410.392118 -92.669614) (xy 410.392118 -94.358714) (xy 409.376118 -94.358714)
				)
			)
		)
		(zone
			(layer "B.Cu")
			(hatch none 0.5)
			(connect_pads
				(clearance 0)
			)
			(min_thickness 0.25)
			(keepout
				(tracks allowed)
				(vias not_allowed)
				(pads allowed)
				(copperpour not_allowed)
				(footprints allowed)
			)
			(placement
				(enabled no)
				(sheetname "")
			)
			(fill
				(thermal_gap 0.5)
				(thermal_bridge_width 0.5)
				(island_removal_mode 0)
			)
			(polygon
				(pts
					(xy 411.154118 -92.669614) (xy 412.170118 -92.669614) (xy 412.170118 -94.358714) (xy 411.154118 -94.358714)
				)
			)
		)
	)
)
